# T6G (Grand Teton) — schematic netlist excerpt (pin names and nets, part order shuffled) for the footprints in the layout excerpt that follows; sources: Cadence DE-HDL packaged netlist, KiCad conversion of 04192023_DAF0TMB3IC0_F0TG_MB_C_brd_V02_OCP.brd

PC301  Q_CAP  0.22UF 16V 10% X7R  pkg 0402  page 212 : A = SW_PVDDCR_CPU0_P1_BOOT4_RC ; B = SW_PVDDCR_CPU0_P1_PH4
R1427  Q_RES  10K 1% CHIP  pkg 0201LF  page 342 : A = RXDET_BYP_RT_CPU1_P2 ; B = GND
C6579  Q_CAP_DIFFBUS  DIFF BUS_0.22UF 6.3V 20% X6S  pkg C0201  page 297 : \1\ = P5E_CPU0_P2_TX_BUF_C_DP<7> ; \2\ = P5E_CPU0_P2_TX_BUF_DP<7>

(kicad_pcb
	(version 20260206)
	(generator "pcbnew")
	(generator_version "10.0")
	(general
		(thickness 1.6)
		(legacy_teardrops no)
	)
	(paper "A4")
	(title_block
		(title "04192023_DAF0TMB3IC0_F0TG_MB_C_brd_V02_OCP.brd")
		(comment 1 "Grand Teton / footprints 2186-2188 of 8354")
	)
	(layers
		(0 "F.Cu" signal "TOP")
		(4 "In1.Cu" signal "GND")
		(6 "In2.Cu" signal "IN1")
		(8 "In3.Cu" signal "GND1")
		(10 "In4.Cu" signal "IN2")
		(12 "In5.Cu" signal "GND2")
		(14 "In6.Cu" signal "IN3")
		(16 "In7.Cu" signal "GND3")
		(18 "In8.Cu" signal "VCC")
		(20 "In9.Cu" signal "VCC1")
		(22 "In10.Cu" signal "GND4")
		(24 "In11.Cu" signal "IN4")
		(26 "In12.Cu" signal "GND5")
		(28 "In13.Cu" signal "IN5")
		(30 "In14.Cu" signal "GND6")
		(32 "In15.Cu" signal "IN6")
		(34 "In16.Cu" signal "GND7")
		(2 "B.Cu" signal "BOTTOM")
		(9 "F.Adhes" user "F.Adhesive")
		(11 "B.Adhes" user "B.Adhesive")
		(13 "F.Paste" user "Package Geometry/Pastemask Top")
		(15 "B.Paste" user "Package Geometry/Pastemask Bottom")
		(5 "F.SilkS" user "Ref Des/Silkscreen Top")
		(7 "B.SilkS" user "Ref Des/Silkscreen Bottom")
		(1 "F.Mask" user "Board Geometry/Soldermask Top")
		(3 "B.Mask" user "Board Geometry/Soldermask Bottom")
		(17 "Dwgs.User" user "User.Drawings")
		(19 "Cmts.User" user "User.Comments")
		(21 "Eco1.User" user "User.Eco1")
		(23 "Eco2.User" user "User.Eco2")
		(25 "Edge.Cuts" user "Board Geometry/Outline")
		(27 "Margin" user)
		(31 "F.CrtYd" user "Package Geometry/Place Bound Top")
		(29 "B.CrtYd" user "Package Geometry/Place Bound Bottom")
		(35 "F.Fab" user "Ref Des/Assembly Top")
		(33 "B.Fab" user "Ref Des/Assembly Bottom")
	)
	(footprint ""
		(layer "F.Cu")
		(at 105.670096 -173.5201 90)
		(property "Reference" "PC301"
			(at 0 0 90)
			(layer "F.SilkS")
			(hide yes)
			(effects
				(font
					(size 1.27 1.27)
				)
			)
		)
		(property "Value" ""
			(at 0 0 90)
			(layer "F.Fab")
			(effects
				(font
					(size 1.27 1.27)
				)
			)
		)
		(duplicate_pad_numbers_are_jumpers no)
		(fp_line
			(start 0.7874 -0.4064)
			(end 0.7874 0.4064)
			(stroke
				(width 0.1524)
				(type default)
			)
			(layer "F.SilkS")
		)
		(fp_line
			(start -0.7874 -0.4064)
			(end 0.7874 -0.4064)
			(stroke
				(width 0.1524)
				(type default)
			)
			(layer "F.SilkS")
		)
		(fp_line
			(start 0.7874 0.4064)
			(end -0.7874 0.4064)
			(stroke
				(width 0.1524)
				(type default)
			)
			(layer "F.SilkS")
		)
		(fp_line
			(start -0.7874 0.4064)
			(end -0.7874 -0.4064)
			(stroke
				(width 0.1524)
				(type default)
			)
			(layer "F.SilkS")
		)
		(fp_line
			(start -0.12065 -0.305054)
			(end -0.12065 -0.2794)
			(stroke
				(width 0.1)
				(type default)
			)
			(layer "F.Fab")
		)
		(fp_line
			(start -0.67945 -0.305054)
			(end -0.12065 -0.305054)
			(stroke
				(width 0.1)
				(type default)
			)
			(layer "F.Fab")
		)
		(fp_line
			(start 0.67945 -0.3048)
			(end 0.67945 0.3048)
			(stroke
				(width 0.1)
				(type default)
			)
			(layer "F.Fab")
		)
		(fp_line
			(start 0.12065 -0.3048)
			(end 0.67945 -0.3048)
			(stroke
				(width 0.1)
				(type default)
			)
			(layer "F.Fab")
		)
		(fp_line
			(start 0.12065 -0.2794)
			(end 0.12065 -0.3048)
			(stroke
				(width 0.1)
				(type default)
			)
			(layer "F.Fab")
		)
		(fp_line
			(start -0.12065 -0.2794)
			(end 0.12065 -0.2794)
			(stroke
				(width 0.1)
				(type default)
			)
			(layer "F.Fab")
		)
		(fp_line
			(start 0.120396 0.2794)
			(end -0.12065 0.2794)
			(stroke
				(width 0.1)
				(type default)
			)
			(layer "F.Fab")
		)
		(fp_line
			(start -0.12065 0.2794)
			(end -0.12065 0.3048)
			(stroke
				(width 0.1)
				(type default)
			)
			(layer "F.Fab")
		)
		(fp_line
			(start 0.67945 0.3048)
			(end 0.120396 0.3048)
			(stroke
				(width 0.1)
				(type default)
			)
			(layer "F.Fab")
		)
		(fp_line
			(start 0.120396 0.3048)
			(end 0.120396 0.2794)
			(stroke
				(width 0.1)
				(type default)
			)
			(layer "F.Fab")
		)
		(fp_line
			(start -0.12065 0.3048)
			(end -0.67945 0.3048)
			(stroke
				(width 0.1)
				(type default)
			)
			(layer "F.Fab")
		)
		(fp_line
			(start -0.67945 0.3048)
			(end -0.67945 -0.305054)
			(stroke
				(width 0.1)
				(type default)
			)
			(layer "F.Fab")
		)
		(pad "1" smd circle
			(at -0.40005 0 90)
			(size 0 0)
			(layers "F.Cu" "F.Mask" "F.Paste")
			(net "SW_PVDDCR_CPU0_P1_BOOT4_RC")
		)
		(pad "2" smd circle
			(at 0.40005 0 90)
			(size 0 0)
			(layers "F.Cu" "F.Mask" "F.Paste")
			(net "SW_PVDDCR_CPU0_P1_PH4")
		)
	)
	(footprint ""
		(layer "F.Cu")
		(at 180.3908 -390.779)
		(property "Reference" "R1427"
			(at 0 0 0)
			(layer "F.SilkS")
			(hide yes)
			(effects
				(font
					(size 1.27 1.27)
				)
			)
		)
		(property "Value" ""
			(at 0 0 0)
			(layer "F.Fab")
			(effects
				(font
					(size 1.27 1.27)
				)
			)
		)
		(duplicate_pad_numbers_are_jumpers no)
		(fp_line
			(start -0.32512 -0.175006)
			(end 0.32512 -0.175006)
			(stroke
				(width 0.1)
				(type default)
			)
			(layer "F.Fab")
		)
		(fp_line
			(start -0.32512 0.175006)
			(end -0.32512 -0.175006)
			(stroke
				(width 0.1)
				(type default)
			)
			(layer "F.Fab")
		)
		(fp_line
			(start 0.32512 -0.175006)
			(end 0.32512 0.175006)
			(stroke
				(width 0.1)
				(type default)
			)
			(layer "F.Fab")
		)
		(fp_line
			(start 0.32512 0.175006)
			(end -0.32512 0.175006)
			(stroke
				(width 0.1)
				(type default)
			)
			(layer "F.Fab")
		)
		(pad "1" smd rect
			(at -0.2667 0)
			(size 0.3048 0.381)
			(layers "F.Cu" "F.Mask" "F.Paste")
			(net "RXDET_BYP_RT_CPU1_P2")
		)
		(pad "2" smd rect
			(at 0.2667 0 180)
			(size 0.3048 0.381)
			(layers "F.Cu" "F.Mask" "F.Paste")
			(net "GND")
		)
	)
	(footprint ""
		(layer "F.Cu")
		(at 393.225782 -416.899344 -90)
		(property "Reference" "C6579"
			(at 0 0 270)
			(layer "F.SilkS")
			(hide yes)
			(effects
				(font
					(size 1.27 1.27)
				)
			)
		)
		(property "Value" ""
			(at 0 0 270)
			(layer "F.Fab")
			(effects
				(font
					(size 1.27 1.27)
				)
			)
		)
		(duplicate_pad_numbers_are_jumpers no)
		(fp_line
			(start -0.299974 0.150114)
			(end -0.299974 -0.150114)
			(stroke
				(width 0.1)
				(type default)
			)
			(layer "F.Fab")
		)
		(fp_line
			(start 0.299974 0.150114)
			(end -0.299974 0.150114)
			(stroke
				(width 0.1)
				(type default)
			)
			(layer "F.Fab")
		)
		(fp_line
			(start -0.299974 -0.150114)
			(end 0.299974 -0.150114)
			(stroke
				(width 0.1)
				(type default)
			)
			(layer "F.Fab")
		)
		(fp_line
			(start 0.299974 -0.150114)
			(end 0.299974 0.150114)
			(stroke
				(width 0.1)
				(type default)
			)
			(layer "F.Fab")
		)
		(pad "1" smd rect
			(at -0.2667 0 270)
			(size 0.3048 0.381)
			(layers "F.Cu" "F.Mask" "F.Paste")
			(net "P5E_CPU0_P2_TX_BUF_C_DP<7>")
		)
		(pad "2" smd rect
			(at 0.2667 0 270)
			(size 0.3048 0.381)
			(layers "F.Cu" "F.Mask" "F.Paste")
			(net "P5E_CPU0_P2_TX_BUF_DP<7>")
		)
	)
)
